# S9S_MB_2U (Grand Teton) — schematic netlist excerpt (pin names and nets, part order shuffled) for the footprints in the layout excerpt that follows; sources: Cadence DE-HDL packaged netlist, KiCad conversion of 03242023_DA0F0TMBIJ0_F0T_Motherboard_J_brd_V01_OCP.brd

R3087  Q_RES  130 1% CHIP  pkg 0402LF  page 253 : A = LED_PWRGD_PVPP_HBM_CPU0 ; B = P3V3_AUX
PC331  Q_CAP  3300PF 50V 10% X7R  pkg 0402  page 266 : A = SH_PVCCIN_CPU0_R ; B = VSENSE_PVCCIN_CPU0_DN

(kicad_pcb
	(version 20260206)
	(generator "pcbnew")
	(generator_version "10.0")
	(general
		(thickness 1.6)
		(legacy_teardrops no)
	)
	(paper "A4")
	(title_block
		(title "03242023_DA0F0TMBIJ0_F0T_Motherboard_J_brd_V01_OCP.brd")
		(comment 1 "Grand Teton / footprints 963-964 of 6105")
	)
	(layers
		(0 "F.Cu" signal "TOP")
		(4 "In1.Cu" signal "GND")
		(6 "In2.Cu" signal "IN1")
		(8 "In3.Cu" signal "GND1")
		(10 "In4.Cu" signal "IN2")
		(12 "In5.Cu" signal "GND2")
		(14 "In6.Cu" signal "IN3")
		(16 "In7.Cu" signal "GND3")
		(18 "In8.Cu" signal "VCC")
		(20 "In9.Cu" signal "VCC1")
		(22 "In10.Cu" signal "GND4")
		(24 "In11.Cu" signal "IN4")
		(26 "In12.Cu" signal "GND5")
		(28 "In13.Cu" signal "IN5")
		(30 "In14.Cu" signal "GND6")
		(32 "In15.Cu" signal "IN6")
		(34 "In16.Cu" signal "GND7")
		(2 "B.Cu" signal "BOTTOM")
		(9 "F.Adhes" user "F.Adhesive")
		(11 "B.Adhes" user "B.Adhesive")
		(13 "F.Paste" user "Package Geometry/Pastemask Top")
		(15 "B.Paste" user "Package Geometry/Pastemask Bottom")
		(5 "F.SilkS" user "Ref Des/Silkscreen Top")
		(7 "B.SilkS" user "Ref Des/Silkscreen Bottom")
		(1 "F.Mask" user "Board Geometry/Soldermask Top")
		(3 "B.Mask" user "Board Geometry/Soldermask Bottom")
		(17 "Dwgs.User" user "User.Drawings")
		(19 "Cmts.User" user "User.Comments")
		(21 "Eco1.User" user "User.Eco1")
		(23 "Eco2.User" user "User.Eco2")
		(25 "Edge.Cuts" user "Board Geometry/Outline")
		(27 "Margin" user)
		(31 "F.CrtYd" user "Package Geometry/Place Bound Top")
		(29 "B.CrtYd" user "Package Geometry/Place Bound Bottom")
		(35 "F.Fab" user "Ref Des/Assembly Top")
		(33 "B.Fab" user "Ref Des/Assembly Bottom")
	)
	(footprint ""
		(layer "F.Cu")
		(at 77.910944 -74.901552 -90)
		(property "Reference" "R3087"
			(at 0 0 270)
			(layer "F.SilkS")
			(hide yes)
			(effects
				(font
					(size 1.27 1.27)
				)
			)
		)
		(property "Value" ""
			(at 0 0 270)
			(layer "F.Fab")
			(effects
				(font
					(size 1.27 1.27)
				)
			)
		)
		(duplicate_pad_numbers_are_jumpers no)
		(fp_line
			(start -0.7874 0.4064)
			(end -0.7874 -0.4064)
			(stroke
				(width 0.1524)
				(type default)
			)
			(layer "F.SilkS")
		)
		(fp_line
			(start 0.7874 0.4064)
			(end -0.7874 0.4064)
			(stroke
				(width 0.1524)
				(type default)
			)
			(layer "F.SilkS")
		)
		(fp_line
			(start -0.7874 -0.4064)
			(end 0.7874 -0.4064)
			(stroke
				(width 0.1524)
				(type default)
			)
			(layer "F.SilkS")
		)
		(fp_line
			(start 0.7874 -0.4064)
			(end 0.7874 0.4064)
			(stroke
				(width 0.1524)
				(type default)
			)
			(layer "F.SilkS")
		)
		(fp_line
			(start -0.67945 0.3048)
			(end -0.67945 -0.305054)
			(stroke
				(width 0.1)
				(type default)
			)
			(layer "F.Fab")
		)
		(fp_line
			(start -0.12065 0.3048)
			(end -0.67945 0.3048)
			(stroke
				(width 0.1)
				(type default)
			)
			(layer "F.Fab")
		)
		(fp_line
			(start 0.120396 0.3048)
			(end 0.120396 0.2794)
			(stroke
				(width 0.1)
				(type default)
			)
			(layer "F.Fab")
		)
		(fp_line
			(start 0.67945 0.3048)
			(end 0.120396 0.3048)
			(stroke
				(width 0.1)
				(type default)
			)
			(layer "F.Fab")
		)
		(fp_line
			(start -0.12065 0.2794)
			(end -0.12065 0.3048)
			(stroke
				(width 0.1)
				(type default)
			)
			(layer "F.Fab")
		)
		(fp_line
			(start 0.120396 0.2794)
			(end -0.12065 0.2794)
			(stroke
				(width 0.1)
				(type default)
			)
			(layer "F.Fab")
		)
		(fp_line
			(start -0.12065 -0.2794)
			(end 0.12065 -0.2794)
			(stroke
				(width 0.1)
				(type default)
			)
			(layer "F.Fab")
		)
		(fp_line
			(start 0.12065 -0.2794)
			(end 0.12065 -0.3048)
			(stroke
				(width 0.1)
				(type default)
			)
			(layer "F.Fab")
		)
		(fp_line
			(start 0.12065 -0.3048)
			(end 0.67945 -0.3048)
			(stroke
				(width 0.1)
				(type default)
			)
			(layer "F.Fab")
		)
		(fp_line
			(start 0.67945 -0.3048)
			(end 0.67945 0.3048)
			(stroke
				(width 0.1)
				(type default)
			)
			(layer "F.Fab")
		)
		(fp_line
			(start -0.67945 -0.305054)
			(end -0.12065 -0.305054)
			(stroke
				(width 0.1)
				(type default)
			)
			(layer "F.Fab")
		)
		(fp_line
			(start -0.12065 -0.305054)
			(end -0.12065 -0.2794)
			(stroke
				(width 0.1)
				(type default)
			)
			(layer "F.Fab")
		)
		(pad "1" smd circle
			(at -0.40005 0 270)
			(size 0 0)
			(layers "F.Cu" "F.Mask" "F.Paste")
			(net "LED_PWRGD_PVPP_HBM_CPU0")
		)
		(pad "2" smd circle
			(at 0.40005 0 270)
			(size 0 0)
			(layers "F.Cu" "F.Mask" "F.Paste")
			(net "P3V3_AUX")
		)
	)
	(footprint ""
		(layer "F.Cu")
		(at 353.851972 -353.137724)
		(property "Reference" "PC331"
			(at 0 0 0)
			(layer "F.SilkS")
			(hide yes)
			(effects
				(font
					(size 1.27 1.27)
				)
			)
		)
		(property "Value" ""
			(at 0 0 0)
			(layer "F.Fab")
			(effects
				(font
					(size 1.27 1.27)
				)
			)
		)
		(duplicate_pad_numbers_are_jumpers no)
		(fp_line
			(start -0.7874 -0.4064)
			(end 0.7874 -0.4064)
			(stroke
				(width 0.1524)
				(type default)
			)
			(layer "F.SilkS")
		)
		(fp_line
			(start -0.7874 0.4064)
			(end -0.7874 -0.4064)
			(stroke
				(width 0.1524)
				(type default)
			)
			(layer "F.SilkS")
		)
		(fp_line
			(start 0.7874 -0.4064)
			(end 0.7874 0.4064)
			(stroke
				(width 0.1524)
				(type default)
			)
			(layer "F.SilkS")
		)
		(fp_line
			(start 0.7874 0.4064)
			(end -0.7874 0.4064)
			(stroke
				(width 0.1524)
				(type default)
			)
			(layer "F.SilkS")
		)
		(fp_line
			(start -0.67945 -0.305054)
			(end -0.12065 -0.305054)
			(stroke
				(width 0.1)
				(type default)
			)
			(layer "F.Fab")
		)
		(fp_line
			(start -0.67945 0.3048)
			(end -0.67945 -0.305054)
			(stroke
				(width 0.1)
				(type default)
			)
			(layer "F.Fab")
		)
		(fp_line
			(start -0.12065 -0.305054)
			(end -0.12065 -0.2794)
			(stroke
				(width 0.1)
				(type default)
			)
			(layer "F.Fab")
		)
		(fp_line
			(start -0.12065 -0.2794)
			(end 0.12065 -0.2794)
			(stroke
				(width 0.1)
				(type default)
			)
			(layer "F.Fab")
		)
		(fp_line
			(start -0.12065 0.2794)
			(end -0.12065 0.3048)
			(stroke
				(width 0.1)
				(type default)
			)
			(layer "F.Fab")
		)
		(fp_line
			(start -0.12065 0.3048)
			(end -0.67945 0.3048)
			(stroke
				(width 0.1)
				(type default)
			)
			(layer "F.Fab")
		)
		(fp_line
			(start 0.120396 0.2794)
			(end -0.12065 0.2794)
			(stroke
				(width 0.1)
				(type default)
			)
			(layer "F.Fab")
		)
		(fp_line
			(start 0.120396 0.3048)
			(end 0.120396 0.2794)
			(stroke
				(width 0.1)
				(type default)
			)
			(layer "F.Fab")
		)
		(fp_line
			(start 0.12065 -0.3048)
			(end 0.67945 -0.3048)
			(stroke
				(width 0.1)
				(type default)
			)
			(layer "F.Fab")
		)
		(fp_line
			(start 0.12065 -0.2794)
			(end 0.12065 -0.3048)
			(stroke
				(width 0.1)
				(type default)
			)
			(layer "F.Fab")
		)
		(fp_line
			(start 0.67945 -0.3048)
			(end 0.67945 0.3048)
			(stroke
				(width 0.1)
				(type default)
			)
			(layer "F.Fab")
		)
		(fp_line
			(start 0.67945 0.3048)
			(end 0.120396 0.3048)
			(stroke
				(width 0.1)
				(type default)
			)
			(layer "F.Fab")
		)
		(pad "1" smd circle
			(at -0.40005 0)
			(size 0 0)
			(layers "F.Cu" "F.Mask" "F.Paste")
			(net "SH_PVCCIN_CPU0_R")
		)
		(pad "2" smd circle
			(at 0.40005 0)
			(size 0 0)
			(layers "F.Cu" "F.Mask" "F.Paste")
			(net "VSENSE_PVCCIN_CPU0_DN")
		)
	)
)
